(kicad_pcb
	(version 20241229)
	(generator "pcbnew")
	(generator_version "9.0")
	(general
		(thickness 1.6)
		(legacy_teardrops no)
	)
	(paper "A4")
	(title_block
		(title "OCuLink to PCIe adapter")
		(date "2025-06-18")
		(rev "1.0.0")
		(company "Antmicro Ltd")
		(comment 1 "www.antmicro.com")
		(comment 9 "footprints 37-40 of 159")
	)
	(layers
		(0 "F.Cu" signal)
		(4 "In1.Cu" signal)
		(6 "In2.Cu" signal)
		(2 "B.Cu" signal)
		(9 "F.Adhes" user "F.Adhesive")
		(11 "B.Adhes" user "B.Adhesive")
		(13 "F.Paste" user)
		(15 "B.Paste" user)
		(5 "F.SilkS" user "F.Silkscreen")
		(7 "B.SilkS" user "B.Silkscreen")
		(1 "F.Mask" user)
		(3 "B.Mask" user)
		(17 "Dwgs.User" user "User.Drawings")
		(19 "Cmts.User" user "User.Comments")
		(21 "Eco1.User" user "User.Eco1")
		(23 "Eco2.User" user "User.Eco2")
		(25 "Edge.Cuts" user)
		(27 "Margin" user)
		(31 "F.CrtYd" user "F.Courtyard")
		(29 "B.CrtYd" user "B.Courtyard")
		(35 "F.Fab" user)
		(33 "B.Fab" user)
	)
	(footprint "antmicro-footprints:R_0402_1005Metric"
		(layer "F.Cu")
		(at 131.72 151.999999)
		(descr "Resistor SMD 0402")
		(tags "resistor SMD 0402")
		(property "Reference" "R42"
			(at 1.08 0.400001 180)
			(layer "F.SilkS")
			(effects
				(font
					(size 0.7 0.7)
					(thickness 0.15)
				)
				(justify left bottom)
			)
		)
		(property "Value" "R_1k_0402"
			(at -1.011843 1.772046 0)
			(layer "F.Fab")
			(effects
				(font
					(size 0.7 0.7)
					(thickness 0.15)
				)
				(justify left bottom)
			)
		)
		(property "Datasheet" "https://www.bourns.com/docs/product-datasheets/cr.pdf"
			(at 0 0 0)
			(layer "F.Fab")
			(hide yes)
			(effects
				(font
					(size 1.27 1.27)
					(thickness 0.15)
				)
			)
		)
		(property "Description" "SMD Chip Resistor, 1 kohm, ± 1%, 63 mW, 0402 [1005 Metric], Thick Film, General Purpose"
			(at 0 0 0)
			(layer "F.Fab")
			(hide yes)
			(effects
				(font
					(size 1.27 1.27)
					(thickness 0.15)
				)
			)
		)
		(property "MPN" "CR0402-FX-1001GLF"
			(at 0 0 0)
			(unlocked yes)
			(layer "F.Fab")
			(hide yes)
			(effects
				(font
					(size 1 1)
					(thickness 0.15)
				)
			)
		)
		(property "Manufacturer" "Bourns"
			(at 0 0 0)
			(unlocked yes)
			(layer "F.Fab")
			(hide yes)
			(effects
				(font
					(size 1 1)
					(thickness 0.15)
				)
			)
		)
		(property "License" "Apache-2.0"
			(at 0 0 0)
			(unlocked yes)
			(layer "F.Fab")
			(hide yes)
			(effects
				(font
					(size 1 1)
					(thickness 0.15)
				)
			)
		)
		(property "Author" "Antmicro"
			(at 0 0 0)
			(unlocked yes)
			(layer "F.Fab")
			(hide yes)
			(effects
				(font
					(size 1 1)
					(thickness 0.15)
				)
			)
		)
		(property "Val" "1k"
			(at 0 0 0)
			(unlocked yes)
			(layer "F.Fab")
			(hide yes)
			(effects
				(font
					(size 1 1)
					(thickness 0.15)
				)
			)
		)
		(property "Tolerance" "1%"
			(at 0 0 0)
			(unlocked yes)
			(layer "F.Fab")
			(hide yes)
			(effects
				(font
					(size 1 1)
					(thickness 0.15)
				)
			)
		)
		(sheetname "/Power/")
		(sheetfile "power.kicad_sch")
		(attr smd)
		(fp_rect
			(start -0.925 -0.47)
			(end 0.925 0.47)
			(stroke
				(width 0.05)
				(type default)
			)
			(fill no)
			(layer "F.CrtYd")
		)
		(fp_rect
			(start -0.5 -0.25)
			(end 0.5 0.25)
			(stroke
				(width 0.15)
				(type solid)
			)
			(fill no)
			(layer "F.Fab")
		)
		(fp_text user "${REFERENCE}"
			(at 0 0 0)
			(layer "F.Fab")
			(effects
				(font
					(size 0.7 0.7)
					(thickness 0.15)
				)
				(justify left bottom)
			)
		)
		(fp_text user "License: Apache-2.0"
			(at -0.949999 5.169 0)
			(layer "F.Fab")
			(effects
				(font
					(size 0.7 0.7)
					(thickness 0.15)
				)
				(justify left bottom)
			)
		)
		(fp_text user "Author: Antmicro"
			(at -0.95 4.169 0)
			(layer "F.Fab")
			(effects
				(font
					(size 0.7 0.7)
					(thickness 0.15)
				)
				(justify left bottom)
			)
		)
		(pad "1" smd roundrect
			(at -0.48 0)
			(size 0.59 0.64)
			(layers "F.Cu" "F.Mask" "F.Paste")
			(roundrect_rratio 0.25)
			(net 161 "Net-(Q3-D)")
			(pintype "passive")
		)
		(pad "2" smd roundrect
			(at 0.48 0)
			(size 0.59 0.64)
			(layers "F.Cu" "F.Mask" "F.Paste")
			(roundrect_rratio 0.25)
			(net 90 "Net-(D2-C)")
			(pintype "passive")
		)
	)
	(footprint "antmicro-footprints:C_0805_2012Metric"
		(layer "F.Cu")
		(at 132 96.650001)
		(descr "Capacitor SMD 0805")
		(tags "capacitor SMD 0805")
		(property "Reference" "C19"
			(at -4.2 0.349999 180)
			(layer "F.SilkS")
			(effects
				(font
					(size 0.7 0.7)
					(thickness 0.15)
				)
				(justify left bottom)
			)
		)
		(property "Value" "C_22u_25V_0805"
			(at -2.055717 1.963153 0)
			(layer "F.Fab")
			(effects
				(font
					(size 0.7 0.7)
					(thickness 0.15)
				)
				(justify left bottom)
			)
		)
		(property "Datasheet" "https://product.samsungsem.com/mlcc/CL21A226MAYNNN.do"
			(at 0 0 0)
			(layer "F.Fab")
			(hide yes)
			(effects
				(font
					(size 1.27 1.27)
					(thickness 0.15)
				)
			)
		)
		(property "Description" "SMT Multilayer Ceramic Capacitor, 22uF, +/-20%, 25V, X5R, 0805 [2012 Metric]"
			(at 0 0 0)
			(layer "F.Fab")
			(hide yes)
			(effects
				(font
					(size 1.27 1.27)
					(thickness 0.15)
				)
			)
		)
		(property "MPN" "CL21A226MAYNNNE"
			(at 0 0 0)
			(unlocked yes)
			(layer "F.Fab")
			(hide yes)
			(effects
				(font
					(size 1 1)
					(thickness 0.15)
				)
			)
		)
		(property "Manufacturer" "Samsung Electro-Mechanics"
			(at 0 0 0)
			(unlocked yes)
			(layer "F.Fab")
			(hide yes)
			(effects
				(font
					(size 1 1)
					(thickness 0.15)
				)
			)
		)
		(property "License" "Apache-2.0"
			(at 0 0 0)
			(unlocked yes)
			(layer "F.Fab")
			(hide yes)
			(effects
				(font
					(size 1 1)
					(thickness 0.15)
				)
			)
		)
		(property "Author" "Antmicro"
			(at 0 0 0)
			(unlocked yes)
			(layer "F.Fab")
			(hide yes)
			(effects
				(font
					(size 1 1)
					(thickness 0.15)
				)
			)
		)
		(property "Val" "22u"
			(at 0 0 0)
			(unlocked yes)
			(layer "F.Fab")
			(hide yes)
			(effects
				(font
					(size 1 1)
					(thickness 0.15)
				)
			)
		)
		(property "Voltage" "25V"
			(at 0 0 0)
			(unlocked yes)
			(layer "F.Fab")
			(hide yes)
			(effects
				(font
					(size 1 1)
					(thickness 0.15)
				)
			)
		)
		(property "Dielectric" "X5R"
			(at 0 0 0)
			(unlocked yes)
			(layer "F.Fab")
			(hide yes)
			(effects
				(font
					(size 1 1)
					(thickness 0.15)
				)
			)
		)
		(property "Public" "False"
			(at 0 0 0)
			(unlocked yes)
			(layer "F.Fab")
			(hide yes)
			(effects
				(font
					(size 1 1)
					(thickness 0.15)
				)
			)
		)
		(sheetname "/USB-PD/")
		(sheetfile "usb-pd.kicad_sch")
		(attr smd)
		(fp_line
			(start -0.3 -0.7)
			(end 0.3 -0.7)
			(stroke
				(width 0.15)
				(type solid)
			)
			(layer "F.SilkS")
		)
		(fp_line
			(start -0.3 0.7)
			(end 0.3 0.7)
			(stroke
				(width 0.15)
				(type solid)
			)
			(layer "F.SilkS")
		)
		(fp_rect
			(start 1.95 -0.9)
			(end -1.95 0.9)
			(stroke
				(width 0.05)
				(type default)
			)
			(fill no)
			(layer "F.CrtYd")
		)
		(fp_rect
			(start -0.95 -0.675)
			(end 0.95 0.675)
			(stroke
				(width 0.15)
				(type solid)
			)
			(fill no)
			(layer "F.Fab")
		)
		(fp_text user "Author: Antmicro"
			(at -1.9 5.947 0)
			(layer "F.Fab")
			(effects
				(font
					(size 0.7 0.7)
					(thickness 0.15)
				)
				(justify left bottom)
			)
		)
		(fp_text user "${REFERENCE}"
			(at 0 0 0)
			(layer "F.Fab")
			(effects
				(font
					(size 0.7 0.7)
					(thickness 0.15)
				)
				(justify left bottom)
			)
		)
		(fp_text user "License: Apache-2.0"
			(at -1.9 4.947 0)
			(layer "F.Fab")
			(effects
				(font
					(size 0.7 0.7)
					(thickness 0.15)
				)
				(justify left bottom)
			)
		)
		(pad "1" smd roundrect
			(at -1.1 0)
			(size 1.2 1.3)
			(layers "F.Cu" "F.Mask" "F.Paste")
			(roundrect_rratio 0.25)
			(net 66 "GND")
			(pintype "passive")
		)
		(pad "2" smd roundrect
			(at 1.1 0)
			(size 1.2 1.3)
			(layers "F.Cu" "F.Mask" "F.Paste")
			(roundrect_rratio 0.25)
			(net 187 "/USB-PD/12V_CONV")
			(pintype "passive")
		)
	)
	(footprint "antmicro-footprints:R_0402_1005Metric"
		(layer "F.Cu")
		(at 120.5 128.8)
		(descr "Resistor SMD 0402")
		(tags "resistor SMD 0402")
		(property "Reference" "R54"
			(at -3.3 0.4 180)
			(layer "F.SilkS")
			(effects
				(font
					(size 0.7 0.7)
					(thickness 0.15)
				)
				(justify left bottom)
			)
		)
		(property "Value" "R_10k_0402"
			(at -1.011843 1.772046 0)
			(layer "F.Fab")
			(effects
				(font
					(size 0.7 0.7)
					(thickness 0.15)
				)
				(justify left bottom)
			)
		)
		(property "Datasheet" "https://www.bourns.com/docs/product-datasheets/cr.pdf"
			(at 0 0 0)
			(layer "F.Fab")
			(hide yes)
			(effects
				(font
					(size 1.27 1.27)
					(thickness 0.15)
				)
			)
		)
		(property "Description" "SMD Chip Resistor, 10 kohm, ± 1%, 62.5 mW, 0402 [1005 Metric], Thick Film, General Purpose"
			(at 0 0 0)
			(layer "F.Fab")
			(hide yes)
			(effects
				(font
					(size 1.27 1.27)
					(thickness 0.15)
				)
			)
		)
		(property "MPN" "CR0402-FX-1002GLF"
			(at 0 0 0)
			(unlocked yes)
			(layer "F.Fab")
			(hide yes)
			(effects
				(font
					(size 1 1)
					(thickness 0.15)
				)
			)
		)
		(property "Manufacturer" "Bourns"
			(at 0 0 0)
			(unlocked yes)
			(layer "F.Fab")
			(hide yes)
			(effects
				(font
					(size 1 1)
					(thickness 0.15)
				)
			)
		)
		(property "License" "Apache-2.0"
			(at 0 0 0)
			(unlocked yes)
			(layer "F.Fab")
			(hide yes)
			(effects
				(font
					(size 1 1)
					(thickness 0.15)
				)
			)
		)
		(property "Author" "Antmicro"
			(at 0 0 0)
			(unlocked yes)
			(layer "F.Fab")
			(hide yes)
			(effects
				(font
					(size 1 1)
					(thickness 0.15)
				)
			)
		)
		(property "Val" "10k"
			(at 0 0 0)
			(unlocked yes)
			(layer "F.Fab")
			(hide yes)
			(effects
				(font
					(size 1 1)
					(thickness 0.15)
				)
			)
		)
		(property "Tolerance" "1%"
			(at 0 0 0)
			(unlocked yes)
			(layer "F.Fab")
			(hide yes)
			(effects
				(font
					(size 1 1)
					(thickness 0.15)
				)
			)
		)
		(sheetname "/Power/")
		(sheetfile "power.kicad_sch")
		(attr smd)
		(fp_rect
			(start -0.925 -0.47)
			(end 0.925 0.47)
			(stroke
				(width 0.05)
				(type default)
			)
			(fill no)
			(layer "F.CrtYd")
		)
		(fp_rect
			(start -0.5 -0.25)
			(end 0.5 0.25)
			(stroke
				(width 0.15)
				(type solid)
			)
			(fill no)
			(layer "F.Fab")
		)
		(fp_text user "Author: Antmicro"
			(at -0.95 4.169 0)
			(layer "F.Fab")
			(effects
				(font
					(size 0.7 0.7)
					(thickness 0.15)
				)
				(justify left bottom)
			)
		)
		(fp_text user "License: Apache-2.0"
			(at -0.949999 5.169 0)
			(layer "F.Fab")
			(effects
				(font
					(size 0.7 0.7)
					(thickness 0.15)
				)
				(justify left bottom)
			)
		)
		(fp_text user "${REFERENCE}"
			(at 0 0 0)
			(layer "F.Fab")
			(effects
				(font
					(size 0.7 0.7)
					(thickness 0.15)
				)
				(justify left bottom)
			)
		)
		(pad "1" smd roundrect
			(at -0.48 0)
			(size 0.59 0.64)
			(layers "F.Cu" "F.Mask" "F.Paste")
			(roundrect_rratio 0.25)
			(net 87 "+12V")
			(pintype "passive")
		)
		(pad "2" smd roundrect
			(at 0.48 0)
			(size 0.59 0.64)
			(layers "F.Cu" "F.Mask" "F.Paste")
			(roundrect_rratio 0.25)
			(net 106 "/Power/3V3_EN")
			(pintype "passive")
		)
	)
	(footprint "antmicro-footprints:R_0402_1005Metric"
		(layer "F.Cu")
		(at 154.312 51.001)
		(descr "Resistor SMD 0402")
		(tags "resistor SMD 0402")
		(property "Reference" "R18"
			(at 1.088 0.399 180)
			(layer "F.SilkS")
			(effects
				(font
					(size 0.7 0.7)
					(thickness 0.15)
				)
				(justify left bottom)
			)
		)
		(property "Value" "R_2k_0402"
			(at -1.011843 1.772046 0)
			(layer "F.Fab")
			(effects
				(font
					(size 0.7 0.7)
					(thickness 0.15)
				)
				(justify left bottom)
			)
		)
		(property "Datasheet" "https://www.bourns.com/docs/product-datasheets/cr.pdf"
			(at 0 0 0)
			(layer "F.Fab")
			(hide yes)
			(effects
				(font
					(size 1.27 1.27)
					(thickness 0.15)
				)
			)
		)
		(property "Description" "SMD Chip Resistor, 2 kohm, ± 1%, 62.5 mW, 0402 [1005 Metric], Thick Film, General Purpose"
			(at 0 0 0)
			(layer "F.Fab")
			(hide yes)
			(effects
				(font
					(size 1.27 1.27)
					(thickness 0.15)
				)
			)
		)
		(property "MPN" "CR0402-FX-2001GLF"
			(at 0 0 0)
			(unlocked yes)
			(layer "F.Fab")
			(hide yes)
			(effects
				(font
					(size 1 1)
					(thickness 0.15)
				)
			)
		)
		(property "Manufacturer" "Bourns"
			(at 0 0 0)
			(unlocked yes)
			(layer "F.Fab")
			(hide yes)
			(effects
				(font
					(size 1 1)
					(thickness 0.15)
				)
			)
		)
		(property "License" "Apache-2.0"
			(at 0 0 0)
			(unlocked yes)
			(layer "F.Fab")
			(hide yes)
			(effects
				(font
					(size 1 1)
					(thickness 0.15)
				)
			)
		)
		(property "Author" "Antmicro"
			(at 0 0 0)
			(unlocked yes)
			(layer "F.Fab")
			(hide yes)
			(effects
				(font
					(size 1 1)
					(thickness 0.15)
				)
			)
		)
		(property "Val" "2k"
			(at 0 0 0)
			(unlocked yes)
			(layer "F.Fab")
			(hide yes)
			(effects
				(font
					(size 1 1)
					(thickness 0.15)
				)
			)
		)
		(property "Tolerance" "1%"
			(at 0 0 0)
			(unlocked yes)
			(layer "F.Fab")
			(hide yes)
			(effects
				(font
					(size 1 1)
					(thickness 0.15)
				)
			)
		)
		(sheetname "/USB-PD/")
		(sheetfile "usb-pd.kicad_sch")
		(attr smd)
		(fp_rect
			(start -0.925 -0.47)
			(end 0.925 0.47)
			(stroke
				(width 0.05)
				(type default)
			)
			(fill no)
			(layer "F.CrtYd")
		)
		(fp_rect
			(start -0.5 -0.25)
			(end 0.5 0.25)
			(stroke
				(width 0.15)
				(type solid)
			)
			(fill no)
			(layer "F.Fab")
		)
		(fp_text user "${REFERENCE}"
			(at 0 0 0)
			(layer "F.Fab")
			(effects
				(font
					(size 0.7 0.7)
					(thickness 0.15)
				)
				(justify left bottom)
			)
		)
		(fp_text user "License: Apache-2.0"
			(at -0.949999 5.169 0)
			(layer "F.Fab")
			(effects
				(font
					(size 0.7 0.7)
					(thickness 0.15)
				)
				(justify left bottom)
			)
		)
		(fp_text user "Author: Antmicro"
			(at -0.95 4.169 0)
			(layer "F.Fab")
			(effects
				(font
					(size 0.7 0.7)
					(thickness 0.15)
				)
				(justify left bottom)
			)
		)
		(pad "1" smd roundrect
			(at -0.48 0)
			(size 0.59 0.64)
			(layers "F.Cu" "F.Mask" "F.Paste")
			(roundrect_rratio 0.25)
			(net 142 "/USB-PD/SCL")
			(pintype "passive")
		)
		(pad "2" smd roundrect
			(at 0.48 0)
			(size 0.59 0.64)
			(layers "F.Cu" "F.Mask" "F.Paste")
			(roundrect_rratio 0.25)
			(net 117 "/USB-PD/VDDD_3V3")
			(pintype "passive")
		)
	)
)
